(kicad_pcb
	(version 20260206)
	(generator "pcbnew")
	(generator_version "10.0")
	(general
		(thickness 1.6)
		(legacy_teardrops no)
	)
	(paper "A4")
	(title_block
		(title "baseboard — 13948-1b.1110WZS1818.brd")
		(comment 1 "Honey Badger (Wiwynn) / footprints 1608-1614 of 2523")
	)
	(layers
		(0 "F.Cu" signal "TOP")
		(4 "In1.Cu" signal "L2GND")
		(6 "In2.Cu" signal "L3")
		(8 "In3.Cu" signal "L4VCC")
		(10 "In4.Cu" signal "L5VCC")
		(12 "In5.Cu" signal "L6")
		(14 "In6.Cu" signal "L7GND")
		(2 "B.Cu" signal "BOTTOM")
		(9 "F.Adhes" user "F.Adhesive")
		(11 "B.Adhes" user "B.Adhesive")
		(13 "F.Paste" user "Package Geometry/Pastemask Top")
		(15 "B.Paste" user "Package Geometry/Pastemask Bottom")
		(5 "F.SilkS" user "Ref Des/Silkscreen Top")
		(7 "B.SilkS" user "Ref Des/Silkscreen Bottom")
		(1 "F.Mask" user "Board Geometry/Soldermask Top")
		(3 "B.Mask" user "Board Geometry/Soldermask Bottom")
		(17 "Dwgs.User" user "User.Drawings")
		(19 "Cmts.User" user "User.Comments")
		(21 "Eco1.User" user "User.Eco1")
		(23 "Eco2.User" user "User.Eco2")
		(25 "Edge.Cuts" user "Board Geometry/Outline")
		(27 "Margin" user)
		(31 "F.CrtYd" user "Package Geometry/Place Bound Top")
		(29 "B.CrtYd" user "Package Geometry/Place Bound Bottom")
		(35 "F.Fab" user "Ref Des/Assembly Top")
		(33 "B.Fab" user "Ref Des/Assembly Bottom")
	)
	(footprint ""
		(layer "F.Cu")
		(at 271.907 -35.814 90)
		(property "Reference" "PC48"
			(at 0 0 90)
			(layer "F.SilkS")
			(hide yes)
			(effects
				(font
					(size 1.27 1.27)
				)
			)
		)
		(property "Value" "SC2K2P50V3KX-GP"
			(at 0 -2.8194 90)
			(unlocked yes)
			(layer "F.Fab")
			(hide yes)
			(effects
				(font
					(size 1.016 1.016)
					(thickness 0.1524)
				)
			)
		)
		(property "Device Type" "C603"
			(at 0 -4.3434 90)
			(unlocked yes)
			(layer "F.Fab")
			(hide yes)
			(effects
				(font
					(size 1.016 1.016)
					(thickness 0.1524)
				)
			)
		)
		(duplicate_pad_numbers_are_jumpers no)
		(fp_line
			(start 0.508 0)
			(end -0.508 0)
			(stroke
				(width 0.2032)
				(type default)
			)
			(layer "F.SilkS")
		)
		(fp_rect
			(start -0.5842 1.3335)
			(end 0.5842 -1.3335)
			(stroke
				(width 0)
				(type default)
			)
			(fill no)
			(layer "F.CrtYd")
		)
		(fp_rect
			(start -0.5842 1.3335)
			(end 0.5842 -1.3335)
			(stroke
				(width 0)
				(type default)
			)
			(fill no)
			(layer "F.Fab")
		)
		(pad "1" smd custom
			(at 0 -0.762 90)
			(size 0.2159 0.2159)
			(layers "F.Cu" "F.Mask" "F.Paste")
			(net "P1V8_STBY_LL")
			(options
				(clearance outline)
				(anchor circle)
			)
			(primitives
				(gr_poly
					(pts
						(arc
							(start -0.3302 -0.4318)
							(mid -0.402042 -0.402042)
							(end -0.4318 -0.3302)
						)
						(arc
							(start -0.4318 0.3302)
							(mid -0.402042 0.402042)
							(end -0.3302 0.4318)
						)
						(arc
							(start 0.3302 0.4318)
							(mid 0.402042 0.402042)
							(end 0.4318 0.3302)
						)
						(arc
							(start 0.4318 -0.3302)
							(mid 0.402042 -0.402042)
							(end 0.3302 -0.4318)
						)
					)
					(width 0)
					(fill yes)
				)
			)
		)
		(pad "2" smd custom
			(at 0 0.762 90)
			(size 0.2159 0.2159)
			(layers "F.Cu" "F.Mask" "F.Paste")
			(net "P1V8_STBY_SNB")
			(options
				(clearance outline)
				(anchor circle)
			)
			(primitives
				(gr_poly
					(pts
						(arc
							(start -0.3302 -0.4318)
							(mid -0.402042 -0.402042)
							(end -0.4318 -0.3302)
						)
						(arc
							(start -0.4318 0.3302)
							(mid -0.402042 0.402042)
							(end -0.3302 0.4318)
						)
						(arc
							(start 0.3302 0.4318)
							(mid 0.402042 0.402042)
							(end 0.4318 0.3302)
						)
						(arc
							(start 0.4318 -0.3302)
							(mid 0.402042 -0.402042)
							(end 0.3302 -0.4318)
						)
					)
					(width 0)
					(fill yes)
				)
			)
		)
	)
	(footprint ""
		(layer "F.Cu")
		(at 117.856 -50.038 -90)
		(property "Reference" "SR615"
			(at 0 0 270)
			(layer "F.SilkS")
			(hide yes)
			(effects
				(font
					(size 1.27 1.27)
				)
			)
		)
		(property "Value" "2K2R2F-GP"
			(at 0.064008 -3.993896 270)
			(unlocked yes)
			(layer "F.Fab")
			(hide yes)
			(effects
				(font
					(size 1.016 1.016)
					(thickness 0.1524)
				)
			)
		)
		(property "Device Type" "R402H16"
			(at 0.064008 -5.517896 270)
			(unlocked yes)
			(layer "F.Fab")
			(hide yes)
			(effects
				(font
					(size 1.016 1.016)
					(thickness 0.1524)
				)
			)
		)
		(duplicate_pad_numbers_are_jumpers no)
		(fp_line
			(start -0.508 -0.9398)
			(end -0.508 0.9398)
			(stroke
				(width 0.1524)
				(type default)
			)
			(layer "F.SilkS")
		)
		(fp_line
			(start 0.508 -0.9398)
			(end -0.508 -0.9398)
			(stroke
				(width 0.1524)
				(type default)
			)
			(layer "F.SilkS")
		)
		(fp_rect
			(start -0.508 0.9398)
			(end 0.508 -0.9398)
			(stroke
				(width 0)
				(type default)
			)
			(fill no)
			(layer "F.CrtYd")
		)
		(fp_rect
			(start -0.508 0.9398)
			(end 0.508 -0.9398)
			(stroke
				(width 0)
				(type default)
			)
			(fill no)
			(layer "F.Fab")
		)
		(pad "1" smd custom
			(at 0 -0.4445 270)
			(size 0.1397 0.1397)
			(layers "F.Cu" "F.Mask" "F.Paste")
			(net "P1V8_C")
			(options
				(clearance outline)
				(anchor circle)
			)
			(primitives
				(gr_poly
					(pts
						(arc
							(start -0.1778 -0.2794)
							(mid -0.249642 -0.249642)
							(end -0.2794 -0.1778)
						)
						(arc
							(start -0.2794 0.1778)
							(mid -0.249642 0.249642)
							(end -0.1778 0.2794)
						)
						(arc
							(start 0.1778 0.2794)
							(mid 0.249642 0.249642)
							(end 0.2794 0.1778)
						)
						(arc
							(start 0.2794 -0.1778)
							(mid 0.249642 -0.249642)
							(end 0.1778 -0.2794)
						)
					)
					(width 0)
					(fill yes)
				)
			)
		)
		(pad "2" smd custom
			(at 0 0.4445 270)
			(size 0.1397 0.1397)
			(layers "F.Cu" "F.Mask" "F.Paste")
			(net "SBL_SDA")
			(options
				(clearance outline)
				(anchor circle)
			)
			(primitives
				(gr_poly
					(pts
						(arc
							(start -0.1778 -0.2794)
							(mid -0.249642 -0.249642)
							(end -0.2794 -0.1778)
						)
						(arc
							(start -0.2794 0.1778)
							(mid -0.249642 0.249642)
							(end -0.1778 0.2794)
						)
						(arc
							(start 0.1778 0.2794)
							(mid 0.249642 0.249642)
							(end 0.2794 0.1778)
						)
						(arc
							(start 0.2794 -0.1778)
							(mid 0.249642 -0.249642)
							(end 0.1778 -0.2794)
						)
					)
					(width 0)
					(fill yes)
				)
			)
		)
	)
	(footprint ""
		(layer "F.Cu")
		(at 90.683842 -120.340882 90)
		(property "Reference" "SR752"
			(at 0 0 90)
			(layer "F.SilkS")
			(hide yes)
			(effects
				(font
					(size 1.27 1.27)
				)
			)
		)
		(property "Value" "4K7R2F-GP"
			(at 0.064008 -3.993896 90)
			(unlocked yes)
			(layer "F.Fab")
			(hide yes)
			(effects
				(font
					(size 1.016 1.016)
					(thickness 0.1524)
				)
			)
		)
		(property "Device Type" "R402H16"
			(at 0.064008 -5.517896 90)
			(unlocked yes)
			(layer "F.Fab")
			(hide yes)
			(effects
				(font
					(size 1.016 1.016)
					(thickness 0.1524)
				)
			)
		)
		(duplicate_pad_numbers_are_jumpers no)
		(fp_line
			(start 0.508 -0.9398)
			(end -0.508 -0.9398)
			(stroke
				(width 0.1524)
				(type default)
			)
			(layer "F.SilkS")
		)
		(fp_line
			(start -0.508 -0.9398)
			(end -0.508 0.9398)
			(stroke
				(width 0.1524)
				(type default)
			)
			(layer "F.SilkS")
		)
		(fp_rect
			(start -0.508 0.9398)
			(end 0.508 -0.9398)
			(stroke
				(width 0)
				(type default)
			)
			(fill no)
			(layer "F.CrtYd")
		)
		(fp_rect
			(start -0.508 0.9398)
			(end 0.508 -0.9398)
			(stroke
				(width 0)
				(type default)
			)
			(fill no)
			(layer "F.Fab")
		)
		(pad "1" smd custom
			(at 0 -0.4445 90)
			(size 0.1397 0.1397)
			(layers "F.Cu" "F.Mask" "F.Paste")
			(net "BMC_I2C_F_SDA")
			(options
				(clearance outline)
				(anchor circle)
			)
			(primitives
				(gr_poly
					(pts
						(arc
							(start -0.1778 -0.2794)
							(mid -0.249642 -0.249642)
							(end -0.2794 -0.1778)
						)
						(arc
							(start -0.2794 0.1778)
							(mid -0.249642 0.249642)
							(end -0.1778 0.2794)
						)
						(arc
							(start 0.1778 0.2794)
							(mid 0.249642 0.249642)
							(end 0.2794 0.1778)
						)
						(arc
							(start 0.2794 -0.1778)
							(mid 0.249642 -0.249642)
							(end 0.1778 -0.2794)
						)
					)
					(width 0)
					(fill yes)
				)
			)
		)
		(pad "2" smd custom
			(at 0 0.4445 90)
			(size 0.1397 0.1397)
			(layers "F.Cu" "F.Mask" "F.Paste")
			(net "P3V3_STBY")
			(options
				(clearance outline)
				(anchor circle)
			)
			(primitives
				(gr_poly
					(pts
						(arc
							(start -0.1778 -0.2794)
							(mid -0.249642 -0.249642)
							(end -0.2794 -0.1778)
						)
						(arc
							(start -0.2794 0.1778)
							(mid -0.249642 0.249642)
							(end -0.1778 0.2794)
						)
						(arc
							(start 0.1778 0.2794)
							(mid 0.249642 0.249642)
							(end 0.2794 0.1778)
						)
						(arc
							(start 0.2794 -0.1778)
							(mid 0.249642 -0.249642)
							(end 0.1778 -0.2794)
						)
					)
					(width 0)
					(fill yes)
				)
			)
		)
	)
	(footprint ""
		(layer "F.Cu")
		(at 189.357 -38.227 180)
		(property "Reference" "R445"
			(at 0 0 180)
			(layer "F.SilkS")
			(hide yes)
			(effects
				(font
					(size 1.27 1.27)
				)
			)
		)
		(property "Value" "0R2J-2-GP"
			(at 0.064008 -3.993896 180)
			(unlocked yes)
			(layer "F.Fab")
			(hide yes)
			(effects
				(font
					(size 1.016 1.016)
					(thickness 0.1524)
				)
			)
		)
		(property "Device Type" "R402H16"
			(at 0.064008 -5.517896 180)
			(unlocked yes)
			(layer "F.Fab")
			(hide yes)
			(effects
				(font
					(size 1.016 1.016)
					(thickness 0.1524)
				)
			)
		)
		(duplicate_pad_numbers_are_jumpers no)
		(fp_line
			(start 0.508 -0.9398)
			(end -0.508 -0.9398)
			(stroke
				(width 0.1524)
				(type default)
			)
			(layer "F.SilkS")
		)
		(fp_line
			(start -0.508 -0.9398)
			(end -0.508 0.9398)
			(stroke
				(width 0.1524)
				(type default)
			)
			(layer "F.SilkS")
		)
		(fp_rect
			(start -0.508 0.9398)
			(end 0.508 -0.9398)
			(stroke
				(width 0)
				(type default)
			)
			(fill no)
			(layer "F.CrtYd")
		)
		(fp_rect
			(start -0.508 0.9398)
			(end 0.508 -0.9398)
			(stroke
				(width 0)
				(type default)
			)
			(fill no)
			(layer "F.Fab")
		)
		(pad "1" smd custom
			(at 0 -0.4445 180)
			(size 0.1397 0.1397)
			(layers "F.Cu" "F.Mask" "F.Paste")
			(net "GND")
			(options
				(clearance outline)
				(anchor circle)
			)
			(primitives
				(gr_poly
					(pts
						(arc
							(start -0.1778 -0.2794)
							(mid -0.249642 -0.249642)
							(end -0.2794 -0.1778)
						)
						(arc
							(start -0.2794 0.1778)
							(mid -0.249642 0.249642)
							(end -0.1778 0.2794)
						)
						(arc
							(start 0.1778 0.2794)
							(mid 0.249642 0.249642)
							(end 0.2794 0.1778)
						)
						(arc
							(start 0.2794 -0.1778)
							(mid 0.249642 -0.249642)
							(end 0.1778 -0.2794)
						)
					)
					(width 0)
					(fill yes)
				)
			)
		)
		(pad "2" smd custom
			(at 0 0.4445 180)
			(size 0.1397 0.1397)
			(layers "F.Cu" "F.Mask" "F.Paste")
			(net "RMII_BMC_CRS_DV")
			(options
				(clearance outline)
				(anchor circle)
			)
			(primitives
				(gr_poly
					(pts
						(arc
							(start -0.1778 -0.2794)
							(mid -0.249642 -0.249642)
							(end -0.2794 -0.1778)
						)
						(arc
							(start -0.2794 0.1778)
							(mid -0.249642 0.249642)
							(end -0.1778 0.2794)
						)
						(arc
							(start 0.1778 0.2794)
							(mid 0.249642 0.249642)
							(end 0.2794 0.1778)
						)
						(arc
							(start 0.2794 -0.1778)
							(mid 0.249642 -0.249642)
							(end 0.1778 -0.2794)
						)
					)
					(width 0)
					(fill yes)
				)
			)
		)
	)
	(footprint ""
		(layer "F.Cu")
		(at 274.193 -175.641 90)
		(property "Reference" "R348"
			(at 0 0 90)
			(layer "F.SilkS")
			(hide yes)
			(effects
				(font
					(size 1.27 1.27)
				)
			)
		)
		(property "Value" "3K3R2F-2-GP"
			(at 0.064008 -3.993896 90)
			(unlocked yes)
			(layer "F.Fab")
			(hide yes)
			(effects
				(font
					(size 1.016 1.016)
					(thickness 0.1524)
				)
			)
		)
		(property "Device Type" "R402H16"
			(at 0.064008 -5.517896 90)
			(unlocked yes)
			(layer "F.Fab")
			(hide yes)
			(effects
				(font
					(size 1.016 1.016)
					(thickness 0.1524)
				)
			)
		)
		(duplicate_pad_numbers_are_jumpers no)
		(fp_line
			(start 0.508 -0.9398)
			(end -0.508 -0.9398)
			(stroke
				(width 0.1524)
				(type default)
			)
			(layer "F.SilkS")
		)
		(fp_line
			(start -0.508 -0.9398)
			(end -0.508 0.9398)
			(stroke
				(width 0.1524)
				(type default)
			)
			(layer "F.SilkS")
		)
		(fp_rect
			(start -0.508 0.9398)
			(end 0.508 -0.9398)
			(stroke
				(width 0)
				(type default)
			)
			(fill no)
			(layer "F.CrtYd")
		)
		(fp_rect
			(start -0.508 0.9398)
			(end 0.508 -0.9398)
			(stroke
				(width 0)
				(type default)
			)
			(fill no)
			(layer "F.Fab")
		)
		(pad "1" smd custom
			(at 0 -0.4445 90)
			(size 0.1397 0.1397)
			(layers "F.Cu" "F.Mask" "F.Paste")
			(net "P3V3_STBY")
			(options
				(clearance outline)
				(anchor circle)
			)
			(primitives
				(gr_poly
					(pts
						(arc
							(start -0.1778 -0.2794)
							(mid -0.249642 -0.249642)
							(end -0.2794 -0.1778)
						)
						(arc
							(start -0.2794 0.1778)
							(mid -0.249642 0.249642)
							(end -0.1778 0.2794)
						)
						(arc
							(start 0.1778 0.2794)
							(mid 0.249642 0.249642)
							(end 0.2794 0.1778)
						)
						(arc
							(start 0.2794 -0.1778)
							(mid 0.249642 -0.249642)
							(end 0.1778 -0.2794)
						)
					)
					(width 0)
					(fill yes)
				)
			)
		)
		(pad "2" smd custom
			(at 0 0.4445 90)
			(size 0.1397 0.1397)
			(layers "F.Cu" "F.Mask" "F.Paste")
			(net "ROMA10")
			(options
				(clearance outline)
				(anchor circle)
			)
			(primitives
				(gr_poly
					(pts
						(arc
							(start -0.1778 -0.2794)
							(mid -0.249642 -0.249642)
							(end -0.2794 -0.1778)
						)
						(arc
							(start -0.2794 0.1778)
							(mid -0.249642 0.249642)
							(end -0.1778 0.2794)
						)
						(arc
							(start 0.1778 0.2794)
							(mid 0.249642 0.249642)
							(end 0.2794 0.1778)
						)
						(arc
							(start 0.2794 -0.1778)
							(mid 0.249642 -0.249642)
							(end 0.1778 -0.2794)
						)
					)
					(width 0)
					(fill yes)
				)
			)
		)
	)
	(footprint ""
		(layer "F.Cu")
		(at 316.611 -118.618)
		(property "Reference" "PR30"
			(at 0 0 0)
			(layer "F.SilkS")
			(hide yes)
			(effects
				(font
					(size 1.27 1.27)
				)
			)
		)
		(property "Value" "100KR2F-L1-GP"
			(at 0.064008 -3.993896 0)
			(unlocked yes)
			(layer "F.Fab")
			(hide yes)
			(effects
				(font
					(size 1.016 1.016)
					(thickness 0.1524)
				)
			)
		)
		(property "Device Type" "R402H16"
			(at 0.064008 -5.517896 0)
			(unlocked yes)
			(layer "F.Fab")
			(hide yes)
			(effects
				(font
					(size 1.016 1.016)
					(thickness 0.1524)
				)
			)
		)
		(duplicate_pad_numbers_are_jumpers no)
		(fp_line
			(start -0.508 -0.9398)
			(end -0.508 0.9398)
			(stroke
				(width 0.1524)
				(type default)
			)
			(layer "F.SilkS")
		)
		(fp_line
			(start 0.508 -0.9398)
			(end -0.508 -0.9398)
			(stroke
				(width 0.1524)
				(type default)
			)
			(layer "F.SilkS")
		)
		(fp_rect
			(start -0.508 0.9398)
			(end 0.508 -0.9398)
			(stroke
				(width 0)
				(type default)
			)
			(fill no)
			(layer "F.CrtYd")
		)
		(fp_rect
			(start -0.508 0.9398)
			(end 0.508 -0.9398)
			(stroke
				(width 0)
				(type default)
			)
			(fill no)
			(layer "F.Fab")
		)
		(pad "1" smd custom
			(at 0 -0.4445)
			(size 0.1397 0.1397)
			(layers "F.Cu" "F.Mask" "F.Paste")
			(net "AGND_P3V3_STBY")
			(options
				(clearance outline)
				(anchor circle)
			)
			(primitives
				(gr_poly
					(pts
						(arc
							(start -0.1778 -0.2794)
							(mid -0.249642 -0.249642)
							(end -0.2794 -0.1778)
						)
						(arc
							(start -0.2794 0.1778)
							(mid -0.249642 0.249642)
							(end -0.1778 0.2794)
						)
						(arc
							(start 0.1778 0.2794)
							(mid 0.249642 0.249642)
							(end 0.2794 0.1778)
						)
						(arc
							(start 0.2794 -0.1778)
							(mid 0.249642 -0.249642)
							(end 0.1778 -0.2794)
						)
					)
					(width 0)
					(fill yes)
				)
			)
		)
		(pad "2" smd custom
			(at 0 0.4445)
			(size 0.1397 0.1397)
			(layers "F.Cu" "F.Mask" "F.Paste")
			(net "P3V3_STBY_MODE")
			(options
				(clearance outline)
				(anchor circle)
			)
			(primitives
				(gr_poly
					(pts
						(arc
							(start -0.1778 -0.2794)
							(mid -0.249642 -0.249642)
							(end -0.2794 -0.1778)
						)
						(arc
							(start -0.2794 0.1778)
							(mid -0.249642 0.249642)
							(end -0.1778 0.2794)
						)
						(arc
							(start 0.1778 0.2794)
							(mid 0.249642 0.249642)
							(end 0.2794 0.1778)
						)
						(arc
							(start 0.2794 -0.1778)
							(mid 0.249642 -0.249642)
							(end 0.1778 -0.2794)
						)
					)
					(width 0)
					(fill yes)
				)
			)
		)
	)
	(footprint ""
		(layer "F.Cu")
		(at 333.912718 -155.552648 -90)
		(property "Reference" "R549"
			(at 0 0 270)
			(layer "F.SilkS")
			(hide yes)
			(effects
				(font
					(size 1.27 1.27)
				)
			)
		)
		(property "Value" "4K7R2F-GP"
			(at 0.064008 -3.993896 270)
			(unlocked yes)
			(layer "F.Fab")
			(hide yes)
			(effects
				(font
					(size 1.016 1.016)
					(thickness 0.1524)
				)
			)
		)
		(property "Device Type" "R402H16"
			(at 0.064008 -5.517896 270)
			(unlocked yes)
			(layer "F.Fab")
			(hide yes)
			(effects
				(font
					(size 1.016 1.016)
					(thickness 0.1524)
				)
			)
		)
		(duplicate_pad_numbers_are_jumpers no)
		(fp_line
			(start -0.508 -0.9398)
			(end -0.508 0.9398)
			(stroke
				(width 0.1524)
				(type default)
			)
			(layer "F.SilkS")
		)
		(fp_line
			(start 0.508 -0.9398)
			(end -0.508 -0.9398)
			(stroke
				(width 0.1524)
				(type default)
			)
			(layer "F.SilkS")
		)
		(fp_rect
			(start -0.508 0.9398)
			(end 0.508 -0.9398)
			(stroke
				(width 0)
				(type default)
			)
			(fill no)
			(layer "F.CrtYd")
		)
		(fp_rect
			(start -0.508 0.9398)
			(end 0.508 -0.9398)
			(stroke
				(width 0)
				(type default)
			)
			(fill no)
			(layer "F.Fab")
		)
		(pad "1" smd custom
			(at 0 -0.4445 270)
			(size 0.1397 0.1397)
			(layers "F.Cu" "F.Mask" "F.Paste")
			(net "USB_EN_4")
			(options
				(clearance outline)
				(anchor circle)
			)
			(primitives
				(gr_poly
					(pts
						(arc
							(start -0.1778 -0.2794)
							(mid -0.249642 -0.249642)
							(end -0.2794 -0.1778)
						)
						(arc
							(start -0.2794 0.1778)
							(mid -0.249642 0.249642)
							(end -0.1778 0.2794)
						)
						(arc
							(start 0.1778 0.2794)
							(mid 0.249642 0.249642)
							(end 0.2794 0.1778)
						)
						(arc
							(start 0.2794 -0.1778)
							(mid 0.249642 -0.249642)
							(end 0.1778 -0.2794)
						)
					)
					(width 0)
					(fill yes)
				)
			)
		)
		(pad "2" smd custom
			(at 0 0.4445 270)
			(size 0.1397 0.1397)
			(layers "F.Cu" "F.Mask" "F.Paste")
			(net "GND")
			(options
				(clearance outline)
				(anchor circle)
			)
			(primitives
				(gr_poly
					(pts
						(arc
							(start -0.1778 -0.2794)
							(mid -0.249642 -0.249642)
							(end -0.2794 -0.1778)
						)
						(arc
							(start -0.2794 0.1778)
							(mid -0.249642 0.249642)
							(end -0.1778 0.2794)
						)
						(arc
							(start 0.1778 0.2794)
							(mid 0.249642 0.249642)
							(end 0.2794 0.1778)
						)
						(arc
							(start 0.2794 -0.1778)
							(mid 0.249642 -0.249642)
							(end 0.1778 -0.2794)
						)
					)
					(width 0)
					(fill yes)
				)
			)
		)
	)
)
